(kicad_pcb
	(version 20260206)
	(generator "pcbnew")
	(generator_version "10.0")
	(general
		(thickness 1.6)
		(legacy_teardrops no)
	)
	(paper "A4")
	(title_block
		(title "Bryce Canyon_F.DPB_16315-1-OCP.brd")
		(comment 1 "Bryce Canyon / footprints 629-634 of 2223")
	)
	(layers
		(0 "F.Cu" signal "TOP")
		(4 "In1.Cu" signal "L2GND")
		(6 "In2.Cu" signal "L3")
		(8 "In3.Cu" signal "L4GND")
		(10 "In4.Cu" signal "L5")
		(12 "In5.Cu" signal "L6VCC")
		(14 "In6.Cu" signal "L7VCC")
		(16 "In7.Cu" signal "L8")
		(18 "In8.Cu" signal "L9GND")
		(20 "In9.Cu" signal "L10")
		(22 "In10.Cu" signal "L11GND")
		(2 "B.Cu" signal "BOTTOM")
		(9 "F.Adhes" user "F.Adhesive")
		(11 "B.Adhes" user "B.Adhesive")
		(13 "F.Paste" user "Package Geometry/Pastemask Top")
		(15 "B.Paste" user "Package Geometry/Pastemask Bottom")
		(5 "F.SilkS" user "Ref Des/Silkscreen Top")
		(7 "B.SilkS" user "Ref Des/Silkscreen Bottom")
		(1 "F.Mask" user "Board Geometry/Soldermask Top")
		(3 "B.Mask" user "Board Geometry/Soldermask Bottom")
		(17 "Dwgs.User" user "User.Drawings")
		(19 "Cmts.User" user "User.Comments")
		(21 "Eco1.User" user "User.Eco1")
		(23 "Eco2.User" user "User.Eco2")
		(25 "Edge.Cuts" user "Board Geometry/Outline")
		(27 "Margin" user)
		(31 "F.CrtYd" user "Package Geometry/Place Bound Top")
		(29 "B.CrtYd" user "Package Geometry/Place Bound Bottom")
		(35 "F.Fab" user "Ref Des/Assembly Top")
		(33 "B.Fab" user "Ref Des/Assembly Bottom")
	)
	(footprint ""
		(layer "F.Cu")
		(at 471.275918 -44.08805 90)
		(property "Reference" "Q211"
			(at 0 0 90)
			(layer "F.SilkS")
			(hide yes)
			(effects
				(font
					(size 1.27 1.27)
				)
			)
		)
		(property "Value" "2N7002KDW-GP"
			(at -2.3622 -8.2042 90)
			(unlocked yes)
			(layer "F.Fab")
			(hide yes)
			(effects
				(font
					(size 1.016 1.016)
					(thickness 0.1524)
				)
			)
		)
		(property "Device Type" "SOT-363H44"
			(at -2.3622 -10.1092 90)
			(unlocked yes)
			(layer "F.Fab")
			(hide yes)
			(effects
				(font
					(size 1.016 1.016)
					(thickness 0.1524)
				)
			)
		)
		(duplicate_pad_numbers_are_jumpers no)
		(fp_line
			(start 1.4478 -1.7018)
			(end -1.4478 -1.7018)
			(stroke
				(width 0.1524)
				(type default)
			)
			(layer "F.SilkS")
		)
		(fp_line
			(start -1.4478 -1.7018)
			(end -1.4478 1.7018)
			(stroke
				(width 0.1524)
				(type default)
			)
			(layer "F.SilkS")
		)
		(fp_line
			(start -1.27 1.524)
			(end -1.27 0.6604)
			(stroke
				(width 0.4826)
				(type default)
			)
			(layer "F.SilkS")
		)
		(fp_line
			(start 1.4478 1.7018)
			(end 1.4478 -1.7018)
			(stroke
				(width 0.1524)
				(type default)
			)
			(layer "F.SilkS")
		)
		(fp_line
			(start -1.4478 1.7018)
			(end 1.4478 1.7018)
			(stroke
				(width 0.1524)
				(type default)
			)
			(layer "F.SilkS")
		)
		(fp_poly
			(pts
				(xy -1.524 -1.778) (xy 1.524 -1.778) (xy 1.524 1.778) (xy -1.524 1.778)
			)
			(stroke
				(width 0)
				(type default)
			)
			(fill no)
			(layer "F.CrtYd")
		)
		(fp_poly
			(pts
				(xy -1.524 -1.778) (xy 1.524 -1.778) (xy 1.524 1.778) (xy -1.524 1.778)
			)
			(stroke
				(width 0)
				(type default)
			)
			(fill no)
			(layer "F.Fab")
		)
		(pad "1" smd rect
			(at -0.65024 0.9398 90)
			(size 0.4064 1.016)
			(layers "F.Cu" "F.Mask" "F.Paste")
			(net "GND")
		)
		(pad "2" smd rect
			(at 0 0.9398 90)
			(size 0.4064 1.016)
			(layers "F.Cu" "F.Mask" "F.Paste")
			(net "SW_PWR_R_HDD35")
		)
		(pad "3" smd rect
			(at 0.65024 0.9398 90)
			(size 0.4064 1.016)
			(layers "F.Cu" "F.Mask" "F.Paste")
			(net "SW_HDD_P35")
		)
		(pad "4" smd rect
			(at 0.65024 -0.9398 90)
			(size 0.4064 1.016)
			(layers "F.Cu" "F.Mask" "F.Paste")
			(net "GND")
		)
		(pad "5" smd rect
			(at 0 -0.9398 90)
			(size 0.4064 1.016)
			(layers "F.Cu" "F.Mask" "F.Paste")
			(net "SW_HDD_G35")
		)
		(pad "6" smd rect
			(at -0.65024 -0.9398 90)
			(size 0.4064 1.016)
			(layers "F.Cu" "F.Mask" "F.Paste")
			(net "SW_HDD_R35")
		)
	)
	(footprint ""
		(layer "F.Cu")
		(at 221.074488 -345.066112 -90)
		(property "Reference" "R26"
			(at 0 0 270)
			(layer "F.SilkS")
			(hide yes)
			(effects
				(font
					(size 1.27 1.27)
				)
			)
		)
		(property "Value" "4K7R2F-GP"
			(at 0.064008 -3.993896 270)
			(unlocked yes)
			(layer "F.Fab")
			(hide yes)
			(effects
				(font
					(size 1.016 1.016)
					(thickness 0.1524)
				)
			)
		)
		(property "Device Type" "R402H16"
			(at 0.064008 -5.517896 270)
			(unlocked yes)
			(layer "F.Fab")
			(hide yes)
			(effects
				(font
					(size 1.016 1.016)
					(thickness 0.1524)
				)
			)
		)
		(duplicate_pad_numbers_are_jumpers no)
		(fp_line
			(start -0.508 -0.9398)
			(end -0.508 0.9398)
			(stroke
				(width 0.1524)
				(type default)
			)
			(layer "F.SilkS")
		)
		(fp_line
			(start 0.508 -0.9398)
			(end -0.508 -0.9398)
			(stroke
				(width 0.1524)
				(type default)
			)
			(layer "F.SilkS")
		)
		(fp_rect
			(start -0.508 0.9398)
			(end 0.508 -0.9398)
			(stroke
				(width 0)
				(type default)
			)
			(fill no)
			(layer "F.CrtYd")
		)
		(fp_rect
			(start -0.508 0.9398)
			(end 0.508 -0.9398)
			(stroke
				(width 0)
				(type default)
			)
			(fill no)
			(layer "F.Fab")
		)
		(pad "1" smd custom
			(at 0 -0.4445 270)
			(size 0.1397 0.1397)
			(layers "F.Cu" "F.Mask" "F.Paste")
			(net "P3V3_STBY_A")
			(options
				(clearance outline)
				(anchor circle)
			)
			(primitives
				(gr_poly
					(pts
						(arc
							(start -0.1778 -0.2794)
							(mid -0.249642 -0.249642)
							(end -0.2794 -0.1778)
						)
						(arc
							(start -0.2794 0.1778)
							(mid -0.249642 0.249642)
							(end -0.1778 0.2794)
						)
						(arc
							(start 0.1778 0.2794)
							(mid 0.249642 0.249642)
							(end 0.2794 0.1778)
						)
						(arc
							(start 0.2794 -0.1778)
							(mid 0.249642 -0.249642)
							(end 0.1778 -0.2794)
						)
					)
					(width 0)
					(fill yes)
				)
			)
		)
		(pad "2" smd custom
			(at 0 0.4445 270)
			(size 0.1397 0.1397)
			(layers "F.Cu" "F.Mask" "F.Paste")
			(net "VOL_SEN_INT_N")
			(options
				(clearance outline)
				(anchor circle)
			)
			(primitives
				(gr_poly
					(pts
						(arc
							(start -0.1778 -0.2794)
							(mid -0.249642 -0.249642)
							(end -0.2794 -0.1778)
						)
						(arc
							(start -0.2794 0.1778)
							(mid -0.249642 0.249642)
							(end -0.1778 0.2794)
						)
						(arc
							(start 0.1778 0.2794)
							(mid 0.249642 0.249642)
							(end 0.2794 0.1778)
						)
						(arc
							(start 0.2794 -0.1778)
							(mid 0.249642 -0.249642)
							(end 0.1778 -0.2794)
						)
					)
					(width 0)
					(fill yes)
				)
			)
		)
	)
	(footprint ""
		(layer "F.Cu")
		(at 317.947294 -130.419602 -90)
		(property "Reference" "R527"
			(at 0 0 270)
			(layer "F.SilkS")
			(hide yes)
			(effects
				(font
					(size 1.27 1.27)
				)
			)
		)
		(property "Value" "4K7R2J-2-GP"
			(at 0.064008 -3.993896 270)
			(unlocked yes)
			(layer "F.Fab")
			(hide yes)
			(effects
				(font
					(size 1.016 1.016)
					(thickness 0.1524)
				)
			)
		)
		(property "Device Type" "R402H16"
			(at 0.064008 -5.517896 270)
			(unlocked yes)
			(layer "F.Fab")
			(hide yes)
			(effects
				(font
					(size 1.016 1.016)
					(thickness 0.1524)
				)
			)
		)
		(duplicate_pad_numbers_are_jumpers no)
		(fp_line
			(start -0.508 -0.9398)
			(end -0.508 0.9398)
			(stroke
				(width 0.1524)
				(type default)
			)
			(layer "F.SilkS")
		)
		(fp_line
			(start 0.508 -0.9398)
			(end -0.508 -0.9398)
			(stroke
				(width 0.1524)
				(type default)
			)
			(layer "F.SilkS")
		)
		(fp_rect
			(start -0.508 0.9398)
			(end 0.508 -0.9398)
			(stroke
				(width 0)
				(type default)
			)
			(fill no)
			(layer "F.CrtYd")
		)
		(fp_rect
			(start -0.508 0.9398)
			(end 0.508 -0.9398)
			(stroke
				(width 0)
				(type default)
			)
			(fill no)
			(layer "F.Fab")
		)
		(pad "1" smd custom
			(at 0 -0.4445 270)
			(size 0.1397 0.1397)
			(layers "F.Cu" "F.Mask" "F.Paste")
			(net "DRIVE_A_18_FLT_LED")
			(options
				(clearance outline)
				(anchor circle)
			)
			(primitives
				(gr_poly
					(pts
						(arc
							(start -0.1778 -0.2794)
							(mid -0.249642 -0.249642)
							(end -0.2794 -0.1778)
						)
						(arc
							(start -0.2794 0.1778)
							(mid -0.249642 0.249642)
							(end -0.1778 0.2794)
						)
						(arc
							(start 0.1778 0.2794)
							(mid 0.249642 0.249642)
							(end 0.2794 0.1778)
						)
						(arc
							(start 0.2794 -0.1778)
							(mid 0.249642 -0.249642)
							(end 0.1778 -0.2794)
						)
					)
					(width 0)
					(fill yes)
				)
			)
		)
		(pad "2" smd custom
			(at 0 0.4445 270)
			(size 0.1397 0.1397)
			(layers "F.Cu" "F.Mask" "F.Paste")
			(net "GND")
			(options
				(clearance outline)
				(anchor circle)
			)
			(primitives
				(gr_poly
					(pts
						(arc
							(start -0.1778 -0.2794)
							(mid -0.249642 -0.249642)
							(end -0.2794 -0.1778)
						)
						(arc
							(start -0.2794 0.1778)
							(mid -0.249642 0.249642)
							(end -0.1778 0.2794)
						)
						(arc
							(start 0.1778 0.2794)
							(mid 0.249642 0.249642)
							(end 0.2794 0.1778)
						)
						(arc
							(start 0.2794 -0.1778)
							(mid 0.249642 -0.249642)
							(end 0.1778 -0.2794)
						)
					)
					(width 0)
					(fill yes)
				)
			)
		)
	)
	(footprint ""
		(layer "F.Cu")
		(at 261.957566 -341.037672 90)
		(property "Reference" "R385"
			(at 0 0 90)
			(layer "F.SilkS")
			(hide yes)
			(effects
				(font
					(size 1.27 1.27)
				)
			)
		)
		(property "Value" "10KR2F-2-GP"
			(at 0.064008 -3.993896 90)
			(unlocked yes)
			(layer "F.Fab")
			(hide yes)
			(effects
				(font
					(size 1.016 1.016)
					(thickness 0.1524)
				)
			)
		)
		(property "Device Type" "R402H16"
			(at 0.064008 -5.517896 90)
			(unlocked yes)
			(layer "F.Fab")
			(hide yes)
			(effects
				(font
					(size 1.016 1.016)
					(thickness 0.1524)
				)
			)
		)
		(duplicate_pad_numbers_are_jumpers no)
		(fp_line
			(start 0.508 -0.9398)
			(end -0.508 -0.9398)
			(stroke
				(width 0.1524)
				(type default)
			)
			(layer "F.SilkS")
		)
		(fp_line
			(start -0.508 -0.9398)
			(end -0.508 0.9398)
			(stroke
				(width 0.1524)
				(type default)
			)
			(layer "F.SilkS")
		)
		(fp_rect
			(start -0.508 0.9398)
			(end 0.508 -0.9398)
			(stroke
				(width 0)
				(type default)
			)
			(fill no)
			(layer "F.CrtYd")
		)
		(fp_rect
			(start -0.508 0.9398)
			(end 0.508 -0.9398)
			(stroke
				(width 0)
				(type default)
			)
			(fill no)
			(layer "F.Fab")
		)
		(pad "1" smd custom
			(at 0 -0.4445 90)
			(size 0.1397 0.1397)
			(layers "F.Cu" "F.Mask" "F.Paste")
			(net "P3V3_STBY_A")
			(options
				(clearance outline)
				(anchor circle)
			)
			(primitives
				(gr_poly
					(pts
						(arc
							(start -0.1778 -0.2794)
							(mid -0.249642 -0.249642)
							(end -0.2794 -0.1778)
						)
						(arc
							(start -0.2794 0.1778)
							(mid -0.249642 0.249642)
							(end -0.1778 0.2794)
						)
						(arc
							(start 0.1778 0.2794)
							(mid 0.249642 0.249642)
							(end 0.2794 0.1778)
						)
						(arc
							(start 0.2794 -0.1778)
							(mid 0.249642 -0.249642)
							(end 0.1778 -0.2794)
						)
					)
					(width 0)
					(fill yes)
				)
			)
		)
		(pad "2" smd custom
			(at 0 0.4445 90)
			(size 0.1397 0.1397)
			(layers "F.Cu" "F.Mask" "F.Paste")
			(net "SCC_A_TYPE_1")
			(options
				(clearance outline)
				(anchor circle)
			)
			(primitives
				(gr_poly
					(pts
						(arc
							(start -0.1778 -0.2794)
							(mid -0.249642 -0.249642)
							(end -0.2794 -0.1778)
						)
						(arc
							(start -0.2794 0.1778)
							(mid -0.249642 0.249642)
							(end -0.1778 0.2794)
						)
						(arc
							(start 0.1778 0.2794)
							(mid 0.249642 0.249642)
							(end 0.2794 0.1778)
						)
						(arc
							(start 0.2794 -0.1778)
							(mid 0.249642 -0.249642)
							(end 0.1778 -0.2794)
						)
					)
					(width 0)
					(fill yes)
				)
			)
		)
	)
	(footprint ""
		(layer "F.Cu")
		(at 271.81937 -284.734762 180)
		(property "Reference" "R435"
			(at 0 0 180)
			(layer "F.SilkS")
			(hide yes)
			(effects
				(font
					(size 1.27 1.27)
				)
			)
		)
		(property "Value" "1KR2F-3-GP"
			(at 0.064008 -3.993896 180)
			(unlocked yes)
			(layer "F.Fab")
			(hide yes)
			(effects
				(font
					(size 1.016 1.016)
					(thickness 0.1524)
				)
			)
		)
		(property "Device Type" "R402H16"
			(at 0.064008 -5.517896 180)
			(unlocked yes)
			(layer "F.Fab")
			(hide yes)
			(effects
				(font
					(size 1.016 1.016)
					(thickness 0.1524)
				)
			)
		)
		(duplicate_pad_numbers_are_jumpers no)
		(fp_line
			(start 0.508 -0.9398)
			(end -0.508 -0.9398)
			(stroke
				(width 0.1524)
				(type default)
			)
			(layer "F.SilkS")
		)
		(fp_line
			(start -0.508 -0.9398)
			(end -0.508 0.9398)
			(stroke
				(width 0.1524)
				(type default)
			)
			(layer "F.SilkS")
		)
		(fp_rect
			(start -0.508 0.9398)
			(end 0.508 -0.9398)
			(stroke
				(width 0)
				(type default)
			)
			(fill no)
			(layer "F.CrtYd")
		)
		(fp_rect
			(start -0.508 0.9398)
			(end 0.508 -0.9398)
			(stroke
				(width 0)
				(type default)
			)
			(fill no)
			(layer "F.Fab")
		)
		(pad "1" smd custom
			(at 0 -0.4445 180)
			(size 0.1397 0.1397)
			(layers "F.Cu" "F.Mask" "F.Paste")
			(net "P3V3_STBY_A")
			(options
				(clearance outline)
				(anchor circle)
			)
			(primitives
				(gr_poly
					(pts
						(arc
							(start -0.1778 -0.2794)
							(mid -0.249642 -0.249642)
							(end -0.2794 -0.1778)
						)
						(arc
							(start -0.2794 0.1778)
							(mid -0.249642 0.249642)
							(end -0.1778 0.2794)
						)
						(arc
							(start 0.1778 0.2794)
							(mid 0.249642 0.249642)
							(end 0.2794 0.1778)
						)
						(arc
							(start 0.2794 -0.1778)
							(mid 0.249642 -0.249642)
							(end 0.1778 -0.2794)
						)
					)
					(width 0)
					(fill yes)
				)
			)
		)
		(pad "2" smd custom
			(at 0 0.4445 180)
			(size 0.1397 0.1397)
			(layers "F.Cu" "F.Mask" "F.Paste")
			(net "I2C_DRIVE_A_FLT_LED_SDA")
			(options
				(clearance outline)
				(anchor circle)
			)
			(primitives
				(gr_poly
					(pts
						(arc
							(start -0.1778 -0.2794)
							(mid -0.249642 -0.249642)
							(end -0.2794 -0.1778)
						)
						(arc
							(start -0.2794 0.1778)
							(mid -0.249642 0.249642)
							(end -0.1778 0.2794)
						)
						(arc
							(start 0.1778 0.2794)
							(mid 0.249642 0.249642)
							(end 0.2794 0.1778)
						)
						(arc
							(start 0.2794 -0.1778)
							(mid 0.249642 -0.249642)
							(end 0.1778 -0.2794)
						)
					)
					(width 0)
					(fill yes)
				)
			)
		)
	)
	(footprint ""
		(layer "F.Cu")
		(at 48.297846 -281.018742 90)
		(property "Reference" "R160"
			(at 0 0 90)
			(layer "F.SilkS")
			(hide yes)
			(effects
				(font
					(size 1.27 1.27)
				)
			)
		)
		(property "Value" "4K7R2J-2-GP"
			(at 0.064008 -3.993896 90)
			(unlocked yes)
			(layer "F.Fab")
			(hide yes)
			(effects
				(font
					(size 1.016 1.016)
					(thickness 0.1524)
				)
			)
		)
		(property "Device Type" "R402H16"
			(at 0.064008 -5.517896 90)
			(unlocked yes)
			(layer "F.Fab")
			(hide yes)
			(effects
				(font
					(size 1.016 1.016)
					(thickness 0.1524)
				)
			)
		)
		(duplicate_pad_numbers_are_jumpers no)
		(fp_line
			(start 0.508 -0.9398)
			(end -0.508 -0.9398)
			(stroke
				(width 0.1524)
				(type default)
			)
			(layer "F.SilkS")
		)
		(fp_line
			(start -0.508 -0.9398)
			(end -0.508 0.9398)
			(stroke
				(width 0.1524)
				(type default)
			)
			(layer "F.SilkS")
		)
		(fp_rect
			(start -0.508 0.9398)
			(end 0.508 -0.9398)
			(stroke
				(width 0)
				(type default)
			)
			(fill no)
			(layer "F.CrtYd")
		)
		(fp_rect
			(start -0.508 0.9398)
			(end 0.508 -0.9398)
			(stroke
				(width 0)
				(type default)
			)
			(fill no)
			(layer "F.Fab")
		)
		(pad "1" smd custom
			(at 0 -0.4445 90)
			(size 0.1397 0.1397)
			(layers "F.Cu" "F.Mask" "F.Paste")
			(net "P12V_A")
			(options
				(clearance outline)
				(anchor circle)
			)
			(primitives
				(gr_poly
					(pts
						(arc
							(start -0.1778 -0.2794)
							(mid -0.249642 -0.249642)
							(end -0.2794 -0.1778)
						)
						(arc
							(start -0.2794 0.1778)
							(mid -0.249642 0.249642)
							(end -0.1778 0.2794)
						)
						(arc
							(start 0.1778 0.2794)
							(mid 0.249642 0.249642)
							(end 0.2794 0.1778)
						)
						(arc
							(start 0.2794 -0.1778)
							(mid 0.249642 -0.249642)
							(end 0.1778 -0.2794)
						)
					)
					(width 0)
					(fill yes)
				)
			)
		)
		(pad "2" smd custom
			(at 0 0.4445 90)
			(size 0.1397 0.1397)
			(layers "F.Cu" "F.Mask" "F.Paste")
			(net "SW_HDD_P1")
			(options
				(clearance outline)
				(anchor circle)
			)
			(primitives
				(gr_poly
					(pts
						(arc
							(start -0.1778 -0.2794)
							(mid -0.249642 -0.249642)
							(end -0.2794 -0.1778)
						)
						(arc
							(start -0.2794 0.1778)
							(mid -0.249642 0.249642)
							(end -0.1778 0.2794)
						)
						(arc
							(start 0.1778 0.2794)
							(mid 0.249642 0.249642)
							(end 0.2794 0.1778)
						)
						(arc
							(start 0.2794 -0.1778)
							(mid 0.249642 -0.249642)
							(end 0.1778 -0.2794)
						)
					)
					(width 0)
					(fill yes)
				)
			)
		)
	)
)
